# T6G (Grand Teton) — schematic parts with pin connectivity, parts 7600–7739 of 8303; source: Cadence DE-HDL packaged netlist (pstxprt.dat, pstxnet.dat, pstchip.dat)

R6260  Q_RES  0 5% CHIP  pkg 0402LF  page 179 : 1 = USB_HUB2_TI_VDD_MRP_USB3DN_TXDM1 ; 2 = P1V2_CPU0_USB2_DVDD12
R6261  Q_RES  0 5% CHIP  pkg 0402LF  page 178 : 1 = USB_HUB2_TI_USB_SSRXP_DN1_MRP_VDD12 ; 2 = P1V2_CPU0_USB2_DVDD12
R6262  Q_RES  0 5% CHIP  pkg 0402LF  page 179 : 1 = USB_HUB2_TI_VDD_MRP_USB3DN_RXDM1 ; 2 = P1V2_CPU0_USB2_DVDD12
R6263  Q_RES  0 5% CHIP  pkg 0402LF  page 178 : 1 = USB_HUB2_TI_USB_DP_DN3_MRP_VDD12 ; 2 = P1V2_CPU0_USB2_DVDD12
R6264  Q_RES  0 5% CHIP  pkg 0402LF  page 178 : 1 = USB_HUB2_TI_USB_DM_DN3_MRP_VDD33 ; 2 = P3V3_AUX_CPU0_USB2_AVDD33
R6265  Q_RES  0 5% CHIP  pkg 0402LF  page 179 : 1 = USB_HUB2_TI_VDD_MRP_USB3DN_TXDP3 ; 2 = P1V2_CPU0_USB2_DVDD12
R6266  Q_RES  0 5% CHIP  pkg 0402LF  page 178 : 1 = USB_HUB2_TI_USB_SSRXM_DN3_MRP_VDD12 ; 2 = P1V2_CPU0_USB2_DVDD12
R6267  Q_RES  0 5% CHIP  pkg 0402LF  page 179 : 1 = USB_HUB2_TI_VDD_MRP_USB3DN_TXDP4 ; 2 = P1V2_CPU0_USB2_DVDD12
R6268  Q_RES  0 5% CHIP  pkg 0402LF  page 178 : 1 = USB_HUB2_TI_USB_SSRXM_DN4_MRP_VDD12 ; 2 = P1V2_CPU0_USB2_DVDD12
R6269  Q_RES  0 5% CHIP  pkg 0402LF  page 179 : 1 = USB_HUB2_TI_VDD_MRP_USB3DN_RXDP4 ; 2 = P1V2_CPU0_USB2_DVDD12
R6270  Q_RES  0 5% CHIP  pkg 0402LF  page 178 : 1 = P3V3_AUX_CPU0_USB2_AVDD33 ; 2 = USB_HUB2_TI_PWRCTL3_MRP_VDD33
R6271  Q_RES  0 5% CHIP  pkg 0402LF  page 178 : 1 = USB_HUB2_TI_USB_DP_DN1_MRP_CFG_STRAP ; 2 = USB_HUB2_MRP_CFG_STRAP
R6272  Q_RES  200K 1% CHIP  pkg 0402LF  page 178 : 1 = USB_HUB2_MRP_CFG_STRAP ; 2 = GND
R6273  Q_RES  200K 1% EMPTY  pkg 0402LF  page 178 : 1 = P3V3_AUX ; 2 = USB_HUB2_MRP_CFG_STRAP
R6274  Q_RES  0 5% CHIP  pkg 0402LF  page 179 : 1 = USB_HUB2_TI_VDD33_MRP_PROG_FUNC7 ; 2 = P3V3_AUX_CPU0_USB2_AVDD33
R6275  Q_RES  0 5% CHIP  pkg 0402LF  page 179 : 1 = USB_HUB2_TI_VDD33_MRP_PRT_CTL4_GANGPWR ; 2 = P3V3_AUX_CPU0_USB2_AVDD33
R6276  Q_RES  0 5% CHIP  pkg 0402LF  page 179 : 1 = USB_HUB2_TI_VDD33_MRP_PRT_CTL4_GANGPWR ; 2 = USB_HUB2_MRP_PRT_CTL4_GANGPWR
R6277  Q_RES  10K 1% EMPTY  pkg 0402LF  page 179 : 1 = P3V3_AUX ; 2 = USB_HUB2_MRP_PRT_CTL4_GANGPWR
R6278  Q_RES  10K 1% EMPTY  pkg 0402LF  page 179 : 1 = USB_HUB2_MRP_PRT_CTL4_GANGPWR ; 2 = GND
R6279  Q_RES  0 5% CHIP  pkg 0402LF  page 179 : 1 = SMB_USB_CPU0_HUB1_SDA ; 2 = SMB_USB_HUB2_TI_SDA_MRP_PRT_CTL2
R6280  Q_RES  0 5% CHIP  pkg 0402LF  page 179 : 1 = SMB_USB_CPU0_HUB1_SCL ; 2 = SMB_USB_HUB2_TI_SCL_MRP_PRT_CTL1
R6281  Q_RES  1K 1% EMPTY  pkg 0402LF  page 179 : 1 = USB_HUB2_TI_SMBUSZ_MRP_PROG_FUNC2 ; 2 = GND
R6282  Q_RES  1K 1% EMPTY  pkg 0402LF  page 179 : 1 = P3V3_AUX ; 2 = USB_HUB2_TI_SMBUSZ_MRP_PROG_FUNC2
R6283  Q_RES  1K 1% EMPTY  pkg 0402LF  page 179 : 1 = P3V3_AUX ; 2 = USB_HUB2_TI_FULLPWRMGMTZ_MRP_PROG_FUNC3
R6284  Q_RES  10 1% CHIP  pkg 0402LF  page 179 : 1 = USB_HUB2_TI_FULLPWRMGMTZ_MRP_PROG_FUNC3 ; 2 = GND
R6285  Q_RES  0 5% CHIP  pkg 0402LF  page 178 : 1 = USB_HUB2_TI_PWRCTL_POL ; 2 = USB_HUB2_TI_PWRCTL_POL_MRP_VBUS_DET
R6286  Q_RES  0 5% CHIP  pkg 0402LF  page 178 : 1 = USB_HUB2_MRP_VBUS_DET ; 2 = USB_HUB2_TI_PWRCTL_POL_MRP_VBUS_DET
R6287  Q_RES  1K 1% CHIP  pkg 0402LF  page 178 : 1 = P3V3_AUX ; 2 = USB_HUB2_TI_PWRCTL_POL
R6288  Q_RES  1K 1% EMPTY  pkg 0402LF  page 178 : 1 = USB_HUB2_TI_PWRCTL_POL ; 2 = GND
R6289  Q_RES  10K 1% CHIP  pkg 0402LF  page 178 : 1 = P3V3_AUX ; 2 = USB_HUB2_MRP_VBUS_DET
R6290  Q_RES  0 5% CHIP  pkg 0402LF  page 179 : 1 = USB_HUB2_TI_GANGED_MRP_I2C_SLV_CFG0 ; 2 = USB_HUB2_TI_GANGED
R6291  Q_RES  0 5% CHIP  pkg 0402LF  page 179 : 1 = USB_HUB2_TI_GANGED_MRP_I2C_SLV_CFG0 ; 2 = USB_HUB2_MRP_I2C_SLV_CFG0
R6292  Q_RES  1K 1% EMPTY  pkg 0402LF  page 179 : 1 = P3V3_AUX ; 2 = USB_HUB2_TI_GANGED
R6293  Q_RES  4.7K 1% CHIP  pkg 0402LF  page 179 : 1 = USB_HUB2_TI_GANGED ; 2 = GND
R6294  Q_RES  10K 1% CHIP  pkg 0402LF  page 179 : 1 = P3V3_AUX ; 2 = USB_HUB2_MRP_I2C_SLV_CFG0
R6295  Q_RES  0 5% CHIP  pkg 0402LF  page 178 : 1 = USB_HUB2_TI_OVERCCUR4 ; 2 = USB_HUB2_TI_OVERCUR4_MRP_I2C_SLV_CFG1
R6296  Q_RES  0 5% CHIP  pkg 0402LF  page 178 : 1 = USB_HUB2_MRP_I2C_SLV_CFG1 ; 2 = USB_HUB2_TI_OVERCUR4_MRP_I2C_SLV_CFG1
R6297  Q_RES  10K 1% CHIP  pkg 0402LF  page 178 : 1 = P3V3_AUX ; 2 = USB_HUB2_TI_OVERCCUR4
R6298  Q_RES  10K 1% CHIP  pkg 0402LF  page 178 : 1 = P3V3_AUX ; 2 = USB_HUB2_MRP_I2C_SLV_CFG1
R6299  Q_RES  0 5% CHIP  pkg 0402LF  page 178 : 1 = USB_HUB2_TI_OVERCUR3 ; 2 = USB_HUB2_TI_OVERCUR3_MRP_CFG_BC_EN
R6300  Q_RES  0 5% CHIP  pkg 0402LF  page 178 : 1 = USB_HUB2_MRP_CFG_BC_EN ; 2 = USB_HUB2_TI_OVERCUR3_MRP_CFG_BC_EN
R6301  Q_RES  10K 1% CHIP  pkg 0402LF  page 178 : 1 = P3V3_AUX ; 2 = USB_HUB2_TI_OVERCUR3
R6302  Q_RES  200K 1% CHIP  pkg 0402LF  page 178 : 1 = USB_HUB2_MRP_CFG_BC_EN ; 2 = GND
R6303  Q_RES  200K 1% EMPTY  pkg 0402LF  page 178 : 1 = P3V3_AUX ; 2 = USB_HUB2_MRP_CFG_BC_EN
R6304  Q_RES  0 5% CHIP  pkg 0402LF  page 179 : 1 = USB_HUB2_TI_HS_SUSPEND ; 2 = USB_HUB2_TI_HS_SUSPEND_MRP_CFG_NON_REM
R6305  Q_RES  0 5% CHIP  pkg 0402LF  page 179 : 1 = USB_HUB2_MRP_CFG_NON_REM ; 2 = USB_HUB2_TI_HS_SUSPEND_MRP_CFG_NON_REM
R6306  Q_RES  4.7K 1% CHIP  pkg 0402LF  page 179 : 1 = P3V3_AUX ; 2 = USB_HUB2_TI_HS_SUSPEND
R6307  Q_RES  4.7K 1% EMPTY  pkg 0402LF  page 179 : 1 = USB_HUB2_TI_HS_SUSPEND ; 2 = GND
R6308  Q_RES  200K 1% EMPTY  pkg 0402LF  page 179 : 1 = P3V3_AUX ; 2 = USB_HUB2_MRP_CFG_NON_REM
R6309  Q_RES  200K 1% CHIP  pkg 0402LF  page 179 : 1 = USB_HUB2_MRP_CFG_NON_REM ; 2 = GND
R6310  Q_RES  0 5% CHIP  pkg 0402LF  page 178 : 1 = USB_HUB2_TI_OVERCUR1 ; 2 = USB_HUB2_TI_OVERCUR1_MRP_PROG_FUNC4
R6311  Q_RES  0 5% CHIP  pkg 0402LF  page 178 : 1 = SMB_USB_CPU0_HUB1_SDA ; 2 = USB_HUB2_TI_OVERCUR1_MRP_PROG_FUNC4
R6312  Q_RES  10K 1% CHIP  pkg 0402LF  page 178 : 1 = P3V3_AUX ; 2 = USB_HUB2_TI_OVERCUR1
R6313  Q_RES  0 5% CHIP  pkg 0402LF  page 178 : 1 = USB_HUB2_TI_OVERCUR2 ; 2 = USB_HUB2_TI_OVERCUR2_MRP_PROG_FUNC5
R6314  Q_RES  0 5% CHIP  pkg 0402LF  page 178 : 1 = SMB_USB_CPU0_HUB1_SCL ; 2 = USB_HUB2_TI_OVERCUR2_MRP_PROG_FUNC5
R6315  Q_RES  10K 1% CHIP  pkg 0402LF  page 178 : 1 = P3V3_AUX ; 2 = USB_HUB2_TI_OVERCUR2
R6316  Q_RES  0 5% CHIP  pkg 0402LF  page 178 : 1 = USB_HUB2_TI_USB_VBUS ; 2 = USB_HUB2_TI_USB_VBUS_MRP_RESET_N
R6317  Q_RES  0 5% CHIP  pkg 0402LF  page 178 : 1 = USB_HUB2_MRP_RESET_N ; 2 = USB_HUB2_TI_USB_VBUS_MRP_RESET_N
R6318  Q_RES  90.9K 1% CHIP  pkg 0402LF  page 178 : 1 = P5V_AUX ; 2 = USB_HUB2_TI_USB_VBUS
R6319  Q_RES  10K 1% CHIP  pkg 0402LF  page 178 : 1 = USB_HUB2_TI_USB_VBUS ; 2 = GND
R6320  Q_RES  10K 1% EMPTY  pkg 0402LF  page 178 : 1 = P3V3_AUX ; 2 = USB_HUB2_MRP_RESET_N
R6321  Q_RES  47K 0.1% EMPTY  pkg 0402LF  page 178 : 1 = USB_HUB2_MRP_RESET_N ; 2 = GND
R6322  Q_RES  0 5% CHIP  pkg 0402LF  page 178 : 1 = RST_USB_HUB_N ; 2 = USB_HUB2_MRP_RESET_N
R6323  Q_RES  0 5% CHIP  pkg 0402LF  page 178 : 1 = USB_HUB2_TI_TEST ; 2 = USB_HUB2_TI_TEST_MRP_PROG_FUNC6
R6324  Q_RES  0 5% CHIP  pkg 0402LF  page 178 : 1 = USB_HUB2_MRP_PROG_FUNC6 ; 2 = USB_HUB2_TI_TEST_MRP_PROG_FUNC6
R6325  Q_RES  10K 1% CHIP  pkg 0402LF  page 178 : 1 = USB_HUB2_TI_TEST ; 2 = GND
R6326  Q_RES  4.7K 1% CHIP  pkg 0402LF  page 178 : 1 = USB_HUB2_MRP_PROG_FUNC6 ; 2 = GND
R6327  Q_RES  4.7K 1% EMPTY  pkg 0402LF  page 178 : 1 = P3V3_AUX ; 2 = USB_HUB2_MRP_PROG_FUNC6
R6328  Q_RES  0 5% CHIP  pkg 0402LF  page 178 : 1 = RST_USB_HUB_N ; 2 = USB_HUB2_TI_GRSTZ_MRP_PROG_FUNC1
R6329  Q_RES  10K 1% EMPTY  pkg 0402LF  page 178 : 1 = P3V3_AUX ; 2 = USB_HUB2_TI_GRSTZ_MRP_PROG_FUNC1
R6330  Q_RES  4.7K 1% CHIP  pkg 0402LF  page 178 : 1 = GND ; 2 = USB_HUB2_TI_NC_MRP_ATEST
R6331  Q_RES  9.53K 1% CHIP  pkg 0402LF  page 178 : 1 = USB_HUB2_TI_USB_R1_MRP_RBIAS ; 2 = GND
R6332  Q_RES  12K 1% CHIP  pkg 0402LF  page 178 : 1 = USB_HUB2_TI_USB_R1_MRP_RBIAS ; 2 = GND
R6333  Q_RES  47K 0.1% EMPTY  pkg 0402LF  page 178 : 1 = USB_HUB2_TI_GRSTZ_MRP_PROG_FUNC1 ; 2 = GND
R6500  Q_RES  0 5% CHIP  pkg 0402LF  page 188 : 1 = PWRGD_P3V3_EN_R ; 2 = PWRGD_P3V3_EN
R6501  Q_RES  100K 1% CHIP  pkg 0402LF  page 188 : 1 = PWRGD_P3V3_EN_R ; 2 = GND
R6502  Q_RES  2.2K 5% CHIP  pkg 0402LF  page 28 : 1 = CPU0_FORCE_SELFREFRESH ; 2 = GND
R6503  Q_RES  2.2K 5% CHIP  pkg 0402LF  page 55 : 1 = CPU1_FORCE_SELFREFRESH ; 2 = GND
R6504  Q_RES  10K 1% CHIP  pkg 0402LF  page 259 : 1 = P1V8_AUX ; 2 = PU_U38_6
R6505  Q_RES  10K 5% CHIP  pkg 0402LF  page 360 : 1 = P3V3_AUX ; 2 = PWRGD_P1V8_RETIMER_CPU0
R6506  Q_RES  33 5% CHIP  pkg 0402LF  page 360 : 1 = PWRGD_P1V8_RETIMER_CPU0 ; 2 = FM_PWRGD_P1V8_RETIMER_CPU0
R6701  Q_RES  0 5% EMPTY  pkg 0402LF  page 323 : 1 = P1V8_CPU1_RT_1D ; 2 = P1V8_CPU1_RT0_1A_1D
R6702  Q_RES  0 5% EMPTY  pkg 0402LF  page 323 : 1 = P1V8_CPU1_RT0_1A_1D ; 2 = P1V8_CPU1_RT0_1A
R6703  Q_RES  0 5% EMPTY  pkg 0402LF  page 323 : 1 = P1V8_CPU1_RT0_1A_1D ; 2 = P1V8_CPU1_RT0_1A
R6704  Q_RES  0 5% EMPTY  pkg 0603LF  page 323 : 1 = P0V9_CPU1_RT_2D ; 2 = P0V9_CPU1_RT0_2A_2D
R6705  Q_RES  0 5% CHIP  pkg 0603LF  page 323 : 1 = P0V9_CPU1_RT0_2A_2D ; 2 = P0V9_CPU1_RT0_2A
R6706  Q_RES  1K 1% CHIP  pkg 0201LF  page 185 : 1 = P1V8_CPU1_RT_1D ; 2 = SMB_RT_CPU1_P0_ROM_R_SCL
R6707  Q_RES  1K 1% CHIP  pkg 0201LF  page 185 : 1 = P1V8_CPU1_RT_1D ; 2 = SMB_RT_CPU1_P0_ROM_R_SDA
R6708  Q_RES  0 5% CHIP  pkg 0201LF  page 320 : 1 = RST_RT_CPU1_P0_PERST_N ; 2 = RST_RT_CPU1_P0_PERST_R_N
R6709  Q_RES  0 5% CHIP  pkg 0201LF  page 320 : 1 = RST_RT_CPU1_P0_RESET_N ; 2 = RST_RT_CPU1_P0_RESET_R_N
R6710  Q_RES  0 5% CHIP  pkg 0402LF  page 81 : 1 = RST_RT_CPU1_P0_PERST_R_N ; 2 = RST_RT_CPU1_P0_PERST_R2_N
R6711  Q_RES  0 5% CHIP  pkg 0402LF  page 81 : 1 = RST_RT_CPU1_P0_RESET_R_N ; 2 = RST_RT_CPU1_P0_RESET_R2_N
R6712  Q_RES  1K 1% CHIP  pkg 0201LF  page 320 : 1 = P1V8_CPU1_RT_1D ; 2 = RT_CPU1_P0_ADDR3
R6713  Q_RES  1K 1% EMPTY  pkg 0201LF  page 320 : 1 = RT_CPU1_P0_ADDR3 ; 2 = GND
R6714  Q_RES  1K 1% EMPTY  pkg 0201LF  page 320 : 1 = P1V8_CPU1_RT_1D ; 2 = RT_CPU1_P0_ADDR2
R6715  Q_RES  20K 1% CHIP  pkg 0201LF  page 320 : 1 = RT_CPU1_P0_ADDR2 ; 2 = GND
R6716  Q_RES  1K 1% EMPTY  pkg 0201LF  page 320 : 1 = P1V8_CPU1_RT_1D ; 2 = RT_CPU1_P0_ADDR1
R6717  Q_RES  1K 1% CHIP  pkg 0201LF  page 320 : 1 = RT_CPU1_P0_ADDR1 ; 2 = GND
R6718  Q_RES  1K 1% CHIP  pkg 0201LF  page 184 : 1 = P1V8_CPU1_RT_1D ; 2 = SMB_RT_CPU1_P0_R_SDA
R6719  Q_RES  1K 1% CHIP  pkg 0201LF  page 184 : 1 = P1V8_CPU1_RT_1D ; 2 = SMB_RT_CPU1_P0_R_SCL
R6720  Q_RES  10K 1% CHIP  pkg 0201LF  page 320 : 1 = RST_RT_CPU1_P0_PERST_R_N ; 2 = GND
R6721  Q_RES  10K 1% CHIP  pkg 0201LF  page 320 : 1 = RST_RT_CPU1_P0_RESET_R_N ; 2 = GND
R6722  Q_RES  4.7K 5% EMPTY  pkg 0201LF  page 320 : 1 = P1V8_CPU1_RT_1D ; 2 = RT_CPU1_P0_SCAN_MODE
R6723  Q_RES  200 1% CHIP  pkg 0201LF  page 320 : 1 = RT_CPU1_P0_SCAN_MODE ; 2 = GND
R6724  Q_RES  4.7K 5% EMPTY  pkg 0201LF  page 320 : 1 = P1V8_CPU1_RT_1D ; 2 = RST_RT_CPU1_P0_RESET_R_N
R6725  Q_RES  4.7K 5% EMPTY  pkg 0201LF  page 320 : 1 = P1V8_CPU1_RT_1D ; 2 = JTAG_TEST_MODE_RT_CPU1_P0
R6730  Q_RES  1K 1% EMPTY  pkg 0201LF  page 332 : 1 = P1V8_CPU1_RT_1D ; 2 = RT_CPU1_P1_VQPS
R6731  Q_RES  200 1% CHIP  pkg 0201LF  page 332 : 1 = RT_CPU1_P1_VQPS ; 2 = GND
R6732  Q_RES  0 5% CHIP  pkg 0201LF  page 332 : 1 = NCF_A1_CPU1_P1_GND ; 2 = GND
R6733  Q_RES  0 5% CHIP  pkg 0201LF  page 332 : 1 = NCF_CPU1_P1_GND ; 2 = GND
R6734  Q_RES  1K 1% CHIP  pkg 0201LF  page 185 : 1 = P1V8_CPU1_RT_1D ; 2 = SMB_RT_CPU1_P1_ROM_R_SCL
R6735  Q_RES  1K 1% CHIP  pkg 0201LF  page 185 : 1 = P1V8_CPU1_RT_1D ; 2 = SMB_RT_CPU1_P1_ROM_R_SDA
R6736  Q_RES  0 5% CHIP  pkg 0201LF  page 184 : 1 = SMB_RT_CPU1_P1_R_SDA ; 2 = SMB_RT_CPU1_P1_SDA
R6737  Q_RES  0 5% CHIP  pkg 0201LF  page 184 : 1 = SMB_RT_CPU1_P1_R_SCL ; 2 = SMB_RT_CPU1_P1_SCL
R6738  Q_RES  1K 1% CHIP  pkg 0201LF  page 184 : 1 = P1V8_CPU1_RT_1D ; 2 = SMB_RT_CPU1_P1_R_SDA
R6739  Q_RES  1K 1% CHIP  pkg 0201LF  page 184 : 1 = P1V8_CPU1_RT_1D ; 2 = SMB_RT_CPU1_P1_R_SCL
R6740  Q_RES  0 5% CHIP  pkg 0402LF  page 81 : 1 = RST_RT_CPU1_P1_PERST_R_N ; 2 = RST_RT_CPU1_P1_PERST_R2_N
R6741  Q_RES  0 5% CHIP  pkg 0402LF  page 81 : 1 = RST_RT_CPU1_P1_RESET_R_N ; 2 = RST_RT_CPU1_P1_RESET_R2_N
R6742  Q_RES  1K 1% EMPTY  pkg 0402LF  page 358 : 1 = P1V8_AUX ; 2 = RT_BOARD_ID_ID1
R6743  Q_RES  1K 1% EMPTY  pkg 0402LF  page 358 : 1 = P1V8_AUX ; 2 = RT_BOARD_ID_ID0
R6744  Q_RES  1K 1% CHIP  pkg 0402LF  page 358 : 1 = RT_BOARD_ID_ID1 ; 2 = GND
R6745  Q_RES  1K 1% CHIP  pkg 0402LF  page 358 : 1 = RT_BOARD_ID_ID0 ; 2 = GND
R6746  Q_RES  0 5% CHIP  pkg 0201LF  page 184 : 1 = SMB_RT_CPU1_P3_R_SDA ; 2 = SMB_RT_CPU1_P3_SDA
R6747  Q_RES  0 5% CHIP  pkg 0201LF  page 184 : 1 = SMB_RT_CPU1_P3_R_SCL ; 2 = SMB_RT_CPU1_P3_SCL
R6748  Q_RES  0 5% CHIP  pkg 0201LF  page 184 : 1 = SMB_RT_CPU1_P2_R_SDA ; 2 = SMB_RT_CPU1_P2_SDA
R6749  Q_RES  0 5% CHIP  pkg 0201LF  page 184 : 1 = SMB_RT_CPU1_P2_R_SCL ; 2 = SMB_RT_CPU1_P2_SCL
R6750  Q_RES  1K 1% CHIP  pkg 0201LF  page 184 : 1 = P1V8_CPU1_RT_1D ; 2 = SMB_RT_CPU1_P3_R_SDA
R6751  Q_RES  1K 1% CHIP  pkg 0201LF  page 184 : 1 = P1V8_CPU1_RT_1D ; 2 = SMB_RT_CPU1_P3_R_SCL
R6752  Q_RES  1K 1% CHIP  pkg 0201LF  page 184 : 1 = P1V8_CPU1_RT_1D ; 2 = SMB_RT_CPU1_P2_R_SDA
R6753  Q_RES  1K 1% CHIP  pkg 0201LF  page 184 : 1 = P1V8_CPU1_RT_1D ; 2 = SMB_RT_CPU1_P2_R_SCL
R6754  Q_RES  0 5% CHIP  pkg 0201LF  page 184 : 1 = SMB_RT_CPU0_P0_SDA ; 2 = SMB_RT_CPU0_P0_R_SDA
R6755  Q_RES  0 5% CHIP  pkg 0201LF  page 184 : 1 = SMB_RT_CPU0_P0_SCL ; 2 = SMB_RT_CPU0_P0_R_SCL
R6756  Q_RES  0 5% CHIP  pkg 0201LF  page 184 : 1 = SMB_RT_CPU0_P1_SDA ; 2 = SMB_RT_CPU0_P1_R_SDA
R6757  Q_RES  0 5% CHIP  pkg 0201LF  page 184 : 1 = SMB_RT_CPU0_P1_SCL ; 2 = SMB_RT_CPU0_P1_R_SCL
R6758  Q_RES  0 5% CHIP  pkg 0201LF  page 184 : 1 = SMB_RT_CPU0_P3_SDA ; 2 = SMB_RT_CPU0_P3_R_SDA
R6759  Q_RES  0 5% CHIP  pkg 0201LF  page 184 : 1 = SMB_RT_CPU0_P3_SCL ; 2 = SMB_RT_CPU0_P3_R_SCL
R6760  Q_RES  0 5% CHIP  pkg 0201LF  page 184 : 1 = SMB_RT_CPU0_P2_SDA ; 2 = SMB_RT_CPU0_P2_R_SDA
R6761  Q_RES  0 5% CHIP  pkg 0201LF  page 184 : 1 = SMB_RT_CPU0_P2_SCL ; 2 = SMB_RT_CPU0_P2_R_SCL
R6762  Q_RES  1K 1% CHIP  pkg 0201LF  page 184 : 1 = P1V8_CPU0_RT_1D ; 2 = SMB_RT_CPU0_P0_R_SDA
R6763  Q_RES  1K 1% CHIP  pkg 0201LF  page 184 : 1 = P1V8_CPU0_RT_1D ; 2 = SMB_RT_CPU0_P0_R_SCL
